(kicad_pcb
	(version 20260206)
	(generator "pcbnew")
	(generator_version "10.0")
	(general
		(thickness 1.6)
		(legacy_teardrops no)
	)
	(paper "A4")
	(title_block
		(title "03242023_DA0F0TMBIJ0_F0T_Motherboard_J_brd_V01_OCP.brd")
		(comment 1 "Grand Teton / footprint 1065 of 6105 (J26), pads 1-112 of 291")
	)
	(layers
		(0 "F.Cu" signal "TOP")
		(4 "In1.Cu" signal "GND")
		(6 "In2.Cu" signal "IN1")
		(8 "In3.Cu" signal "GND1")
		(10 "In4.Cu" signal "IN2")
		(12 "In5.Cu" signal "GND2")
		(14 "In6.Cu" signal "IN3")
		(16 "In7.Cu" signal "GND3")
		(18 "In8.Cu" signal "VCC")
		(20 "In9.Cu" signal "VCC1")
		(22 "In10.Cu" signal "GND4")
		(24 "In11.Cu" signal "IN4")
		(26 "In12.Cu" signal "GND5")
		(28 "In13.Cu" signal "IN5")
		(30 "In14.Cu" signal "GND6")
		(32 "In15.Cu" signal "IN6")
		(34 "In16.Cu" signal "GND7")
		(2 "B.Cu" signal "BOTTOM")
		(9 "F.Adhes" user "F.Adhesive")
		(11 "B.Adhes" user "B.Adhesive")
		(13 "F.Paste" user "Package Geometry/Pastemask Top")
		(15 "B.Paste" user "Package Geometry/Pastemask Bottom")
		(5 "F.SilkS" user "Ref Des/Silkscreen Top")
		(7 "B.SilkS" user "Ref Des/Silkscreen Bottom")
		(1 "F.Mask" user "Board Geometry/Soldermask Top")
		(3 "B.Mask" user "Board Geometry/Soldermask Bottom")
		(17 "Dwgs.User" user "User.Drawings")
		(19 "Cmts.User" user "User.Comments")
		(21 "Eco1.User" user "User.Eco1")
		(23 "Eco2.User" user "User.Eco2")
		(25 "Edge.Cuts" user "Board Geometry/Outline")
		(27 "Margin" user)
		(31 "F.CrtYd" user "Package Geometry/Place Bound Top")
		(29 "B.CrtYd" user "Package Geometry/Place Bound Bottom")
		(35 "F.Fab" user "Ref Des/Assembly Top")
		(33 "B.Fab" user "Ref Des/Assembly Bottom")
	)
	(footprint ""
		(layer "F.Cu")
		(at 160.86328 -258.091686)
		(property "Reference" "J26"
			(at -3.683 -81.702148 0)
			(unlocked yes)
			(layer "F.SilkS")
			(effects
				(font
					(size 0.7874 0.5842)
					(thickness 0.1524)
				)
				(justify left)
			)
		)
		(property "Value" ""
			(at 0 0 0)
			(layer "F.Fab")
			(effects
				(font
					(size 1.27 1.27)
				)
			)
		)
		(duplicate_pad_numbers_are_jumpers no)
		(pad "1" smd rect
			(at -2.050034 -63.324994 270)
			(size 0.519938 1.4986)
			(layers "F.Cu" "F.Mask" "F.Paste")
			(net "P12V_S3_AUX_CPU1_NVDIMM")
		)
		(pad "2" smd rect
			(at -2.050034 -62.47511 270)
			(size 0.519938 1.4986)
			(layers "F.Cu" "F.Mask" "F.Paste")
			(net "TP_CHE_CPU1_DIMM2_FRU_0")
		)
		(pad "3" smd rect
			(at -2.050034 -61.624972 270)
			(size 0.519938 1.4986)
			(layers "F.Cu" "F.Mask" "F.Paste")
			(net "P3V3_AUX")
		)
		(pad "4" smd rect
			(at -2.050034 -60.775088 270)
			(size 0.519938 1.4986)
			(layers "F.Cu" "F.Mask" "F.Paste")
			(net "I3C_SPD_DDREFGH_CPU1_LVC1_SCL_1")
		)
		(pad "5" smd rect
			(at -2.050034 -59.92495 270)
			(size 0.519938 1.4986)
			(layers "F.Cu" "F.Mask" "F.Paste")
			(net "I3C_SPD_DDREFGH_CPU1_LVC1_SDA")
		)
		(pad "6" smd rect
			(at -2.050034 -59.075066 270)
			(size 0.519938 1.4986)
			(layers "F.Cu" "F.Mask" "F.Paste")
			(net "GND")
		)
		(pad "7" smd rect
			(at -2.050034 -58.224928 270)
			(size 0.519938 1.4986)
			(layers "F.Cu" "F.Mask" "F.Paste")
			(net "M_E_CPU1_SA_DQ<0>")
		)
		(pad "8" smd rect
			(at -2.050034 -57.375044 270)
			(size 0.519938 1.4986)
			(layers "F.Cu" "F.Mask" "F.Paste")
			(net "GND")
		)
		(pad "9" smd rect
			(at -2.050034 -56.524906 270)
			(size 0.519938 1.4986)
			(layers "F.Cu" "F.Mask" "F.Paste")
			(net "M_E_CPU1_SA_DQ<1>")
		)
		(pad "10" smd rect
			(at -2.050034 -55.675022 270)
			(size 0.519938 1.4986)
			(layers "F.Cu" "F.Mask" "F.Paste")
			(net "GND")
		)
		(pad "11" smd rect
			(at -2.050034 -54.824884 270)
			(size 0.519938 1.4986)
			(layers "F.Cu" "F.Mask" "F.Paste")
			(net "M_E_CPU1_SA_DQS_DP<0>")
		)
		(pad "12" smd rect
			(at -2.050034 -53.975 270)
			(size 0.519938 1.4986)
			(layers "F.Cu" "F.Mask" "F.Paste")
			(net "M_E_CPU1_SA_DQS_DN<0>")
		)
		(pad "13" smd rect
			(at -2.050034 -53.125116 270)
			(size 0.519938 1.4986)
			(layers "F.Cu" "F.Mask" "F.Paste")
			(net "GND")
		)
		(pad "14" smd rect
			(at -2.050034 -52.274978 270)
			(size 0.519938 1.4986)
			(layers "F.Cu" "F.Mask" "F.Paste")
			(net "M_E_CPU1_SA_DQ<4>")
		)
		(pad "15" smd rect
			(at -2.050034 -51.425094 270)
			(size 0.519938 1.4986)
			(layers "F.Cu" "F.Mask" "F.Paste")
			(net "GND")
		)
		(pad "16" smd rect
			(at -2.050034 -50.574956 270)
			(size 0.519938 1.4986)
			(layers "F.Cu" "F.Mask" "F.Paste")
			(net "M_E_CPU1_SA_DQ<5>")
		)
		(pad "17" smd rect
			(at -2.050034 -49.725072 270)
			(size 0.519938 1.4986)
			(layers "F.Cu" "F.Mask" "F.Paste")
			(net "GND")
		)
		(pad "18" smd rect
			(at -2.050034 -48.874934 270)
			(size 0.519938 1.4986)
			(layers "F.Cu" "F.Mask" "F.Paste")
			(net "M_E_CPU1_SA_DQ<8>")
		)
		(pad "19" smd rect
			(at -2.050034 -48.02505 270)
			(size 0.519938 1.4986)
			(layers "F.Cu" "F.Mask" "F.Paste")
			(net "GND")
		)
		(pad "20" smd rect
			(at -2.050034 -47.174912 270)
			(size 0.519938 1.4986)
			(layers "F.Cu" "F.Mask" "F.Paste")
			(net "M_E_CPU1_SA_DQ<9>")
		)
		(pad "21" smd rect
			(at -2.050034 -46.325028 270)
			(size 0.519938 1.4986)
			(layers "F.Cu" "F.Mask" "F.Paste")
			(net "GND")
		)
		(pad "22" smd rect
			(at -2.050034 -45.47489 270)
			(size 0.519938 1.4986)
			(layers "F.Cu" "F.Mask" "F.Paste")
			(net "M_E_CPU1_SA_DQS_DP<1>")
		)
		(pad "23" smd rect
			(at -2.050034 -44.625006 270)
			(size 0.519938 1.4986)
			(layers "F.Cu" "F.Mask" "F.Paste")
			(net "M_E_CPU1_SA_DQS_DN<1>")
		)
		(pad "24" smd rect
			(at -2.050034 -43.775122 270)
			(size 0.519938 1.4986)
			(layers "F.Cu" "F.Mask" "F.Paste")
			(net "GND")
		)
		(pad "25" smd rect
			(at -2.050034 -42.924984 270)
			(size 0.519938 1.4986)
			(layers "F.Cu" "F.Mask" "F.Paste")
			(net "M_E_CPU1_SA_DQ<12>")
		)
		(pad "26" smd rect
			(at -2.050034 -42.0751 270)
			(size 0.519938 1.4986)
			(layers "F.Cu" "F.Mask" "F.Paste")
			(net "GND")
		)
		(pad "27" smd rect
			(at -2.050034 -41.224962 270)
			(size 0.519938 1.4986)
			(layers "F.Cu" "F.Mask" "F.Paste")
			(net "M_E_CPU1_SA_DQ<13>")
		)
		(pad "28" smd rect
			(at -2.050034 -40.375078 270)
			(size 0.519938 1.4986)
			(layers "F.Cu" "F.Mask" "F.Paste")
			(net "GND")
		)
		(pad "29" smd rect
			(at -2.050034 -39.52494 270)
			(size 0.519938 1.4986)
			(layers "F.Cu" "F.Mask" "F.Paste")
			(net "M_E_CPU1_SA_DQ<16>")
		)
		(pad "30" smd rect
			(at -2.050034 -38.675056 270)
			(size 0.519938 1.4986)
			(layers "F.Cu" "F.Mask" "F.Paste")
			(net "GND")
		)
		(pad "31" smd rect
			(at -2.050034 -37.824918 270)
			(size 0.519938 1.4986)
			(layers "F.Cu" "F.Mask" "F.Paste")
			(net "M_E_CPU1_SA_DQ<17>")
		)
		(pad "32" smd rect
			(at -2.050034 -36.975034 270)
			(size 0.519938 1.4986)
			(layers "F.Cu" "F.Mask" "F.Paste")
			(net "GND")
		)
		(pad "33" smd rect
			(at -2.050034 -36.124896 270)
			(size 0.519938 1.4986)
			(layers "F.Cu" "F.Mask" "F.Paste")
			(net "M_E_CPU1_SA_DQS_DP<2>")
		)
		(pad "34" smd rect
			(at -2.050034 -35.275012 270)
			(size 0.519938 1.4986)
			(layers "F.Cu" "F.Mask" "F.Paste")
			(net "M_E_CPU1_SA_DQS_DN<2>")
		)
		(pad "35" smd rect
			(at -2.050034 -34.425128 270)
			(size 0.519938 1.4986)
			(layers "F.Cu" "F.Mask" "F.Paste")
			(net "GND")
		)
		(pad "36" smd rect
			(at -2.050034 -33.57499 270)
			(size 0.519938 1.4986)
			(layers "F.Cu" "F.Mask" "F.Paste")
			(net "M_E_CPU1_SA_DQ<20>")
		)
		(pad "37" smd rect
			(at -2.050034 -32.725106 270)
			(size 0.519938 1.4986)
			(layers "F.Cu" "F.Mask" "F.Paste")
			(net "GND")
		)
		(pad "38" smd rect
			(at -2.050034 -31.874968 270)
			(size 0.519938 1.4986)
			(layers "F.Cu" "F.Mask" "F.Paste")
			(net "M_E_CPU1_SA_DQ<21>")
		)
		(pad "39" smd rect
			(at -2.050034 -31.025084 270)
			(size 0.519938 1.4986)
			(layers "F.Cu" "F.Mask" "F.Paste")
			(net "GND")
		)
		(pad "40" smd rect
			(at -2.050034 -30.174946 270)
			(size 0.519938 1.4986)
			(layers "F.Cu" "F.Mask" "F.Paste")
			(net "M_E_CPU1_SA_DQ<24>")
		)
		(pad "41" smd rect
			(at -2.050034 -29.325062 270)
			(size 0.519938 1.4986)
			(layers "F.Cu" "F.Mask" "F.Paste")
			(net "GND")
		)
		(pad "42" smd rect
			(at -2.050034 -28.474924 270)
			(size 0.519938 1.4986)
			(layers "F.Cu" "F.Mask" "F.Paste")
			(net "M_E_CPU1_SA_DQ<25>")
		)
		(pad "43" smd rect
			(at -2.050034 -27.62504 270)
			(size 0.519938 1.4986)
			(layers "F.Cu" "F.Mask" "F.Paste")
			(net "GND")
		)
		(pad "44" smd rect
			(at -2.050034 -26.774902 270)
			(size 0.519938 1.4986)
			(layers "F.Cu" "F.Mask" "F.Paste")
			(net "M_E_CPU1_SA_DQS_DP<3>")
		)
		(pad "45" smd rect
			(at -2.050034 -25.925018 270)
			(size 0.519938 1.4986)
			(layers "F.Cu" "F.Mask" "F.Paste")
			(net "M_E_CPU1_SA_DQS_DN<3>")
		)
		(pad "46" smd rect
			(at -2.050034 -25.07488 270)
			(size 0.519938 1.4986)
			(layers "F.Cu" "F.Mask" "F.Paste")
			(net "GND")
		)
		(pad "47" smd rect
			(at -2.050034 -24.224996 270)
			(size 0.519938 1.4986)
			(layers "F.Cu" "F.Mask" "F.Paste")
			(net "M_E_CPU1_SA_DQ<28>")
		)
		(pad "48" smd rect
			(at -2.050034 -23.375112 270)
			(size 0.519938 1.4986)
			(layers "F.Cu" "F.Mask" "F.Paste")
			(net "GND")
		)
		(pad "49" smd rect
			(at -2.050034 -22.524974 270)
			(size 0.519938 1.4986)
			(layers "F.Cu" "F.Mask" "F.Paste")
			(net "M_E_CPU1_SA_DQ<29>")
		)
		(pad "50" smd rect
			(at -2.050034 -21.67509 270)
			(size 0.519938 1.4986)
			(layers "F.Cu" "F.Mask" "F.Paste")
			(net "GND")
		)
		(pad "51" smd rect
			(at -2.050034 -20.824952 270)
			(size 0.519938 1.4986)
			(layers "F.Cu" "F.Mask" "F.Paste")
			(net "M_E_CPU1_SA_CB<0>")
		)
		(pad "52" smd rect
			(at -2.050034 -19.975068 270)
			(size 0.519938 1.4986)
			(layers "F.Cu" "F.Mask" "F.Paste")
			(net "GND")
		)
		(pad "53" smd rect
			(at -2.050034 -19.12493 270)
			(size 0.519938 1.4986)
			(layers "F.Cu" "F.Mask" "F.Paste")
			(net "M_E_CPU1_SA_CB<1>")
		)
		(pad "54" smd rect
			(at -2.050034 -18.275046 270)
			(size 0.519938 1.4986)
			(layers "F.Cu" "F.Mask" "F.Paste")
			(net "GND")
		)
		(pad "55" smd rect
			(at -2.050034 -17.424908 270)
			(size 0.519938 1.4986)
			(layers "F.Cu" "F.Mask" "F.Paste")
			(net "M_E_CPU1_SA_DQS_DP<4>")
		)
		(pad "56" smd rect
			(at -2.050034 -16.575024 270)
			(size 0.519938 1.4986)
			(layers "F.Cu" "F.Mask" "F.Paste")
			(net "M_E_CPU1_SA_DQS_DN<4>")
		)
		(pad "57" smd rect
			(at -2.050034 -15.724886 270)
			(size 0.519938 1.4986)
			(layers "F.Cu" "F.Mask" "F.Paste")
			(net "GND")
		)
		(pad "58" smd rect
			(at -2.050034 -14.875002 270)
			(size 0.519938 1.4986)
			(layers "F.Cu" "F.Mask" "F.Paste")
			(net "M_E_CPU1_SA_CB<4>")
		)
		(pad "59" smd rect
			(at -2.050034 -14.025118 270)
			(size 0.519938 1.4986)
			(layers "F.Cu" "F.Mask" "F.Paste")
			(net "GND")
		)
		(pad "60" smd rect
			(at -2.050034 -13.17498 270)
			(size 0.519938 1.4986)
			(layers "F.Cu" "F.Mask" "F.Paste")
			(net "M_E_CPU1_SA_CB<5>")
		)
		(pad "61" smd rect
			(at -2.050034 -12.325096 270)
			(size 0.519938 1.4986)
			(layers "F.Cu" "F.Mask" "F.Paste")
			(net "GND")
		)
		(pad "62" smd rect
			(at -2.050034 -11.474958 270)
			(size 0.519938 1.4986)
			(layers "F.Cu" "F.Mask" "F.Paste")
			(net "M_E_CPU1_ALERT_N")
		)
		(pad "63" smd rect
			(at -2.050034 -10.625074 270)
			(size 0.519938 1.4986)
			(layers "F.Cu" "F.Mask" "F.Paste")
			(net "GND")
		)
		(pad "64" smd rect
			(at -2.050034 -9.774936 270)
			(size 0.519938 1.4986)
			(layers "F.Cu" "F.Mask" "F.Paste")
			(net "M_E_CPU1_SA_CS_N<2>")
		)
		(pad "65" smd rect
			(at -2.050034 -8.925052 270)
			(size 0.519938 1.4986)
			(layers "F.Cu" "F.Mask" "F.Paste")
			(net "GND")
		)
		(pad "66" smd rect
			(at -2.050034 -8.074914 270)
			(size 0.519938 1.4986)
			(layers "F.Cu" "F.Mask" "F.Paste")
			(net "M_E_CPU1_SA_CA<0>")
		)
		(pad "67" smd rect
			(at -2.050034 -7.22503 270)
			(size 0.519938 1.4986)
			(layers "F.Cu" "F.Mask" "F.Paste")
			(net "GND")
		)
		(pad "68" smd rect
			(at -2.050034 -6.374892 270)
			(size 0.519938 1.4986)
			(layers "F.Cu" "F.Mask" "F.Paste")
			(net "M_E_CPU1_SA_CA<2>")
		)
		(pad "69" smd rect
			(at -2.050034 -5.525008 270)
			(size 0.519938 1.4986)
			(layers "F.Cu" "F.Mask" "F.Paste")
			(net "GND")
		)
		(pad "70" smd rect
			(at -2.050034 -4.675124 270)
			(size 0.519938 1.4986)
			(layers "F.Cu" "F.Mask" "F.Paste")
			(net "M_E_CPU1_SA_CA<4>")
		)
		(pad "71" smd rect
			(at -2.050034 -3.824986 270)
			(size 0.519938 1.4986)
			(layers "F.Cu" "F.Mask" "F.Paste")
			(net "GND")
		)
		(pad "72" smd rect
			(at -2.050034 -2.975102 270)
			(size 0.519938 1.4986)
			(layers "F.Cu" "F.Mask" "F.Paste")
			(net "M_E_CPU1_SA_CA<6>")
		)
		(pad "73" smd rect
			(at -2.050034 -2.124964 270)
			(size 0.519938 1.4986)
			(layers "F.Cu" "F.Mask" "F.Paste")
			(net "GND")
		)
		(pad "74" smd rect
			(at -2.050034 -1.27508 270)
			(size 0.519938 1.4986)
			(layers "F.Cu" "F.Mask" "F.Paste")
			(net "M_E_CPU1_SA_PAR")
		)
		(pad "75" smd rect
			(at -2.050034 -0.424942 270)
			(size 0.519938 1.4986)
			(layers "F.Cu" "F.Mask" "F.Paste")
			(net "GND")
		)
		(pad "76" smd rect
			(at -2.050034 5.525008 270)
			(size 0.519938 1.4986)
			(layers "F.Cu" "F.Mask" "F.Paste")
			(net "M_E_CPU1_SB_CA<0>")
		)
		(pad "77" smd rect
			(at -2.050034 6.374892 270)
			(size 0.519938 1.4986)
			(layers "F.Cu" "F.Mask" "F.Paste")
			(net "GND")
		)
		(pad "78" smd rect
			(at -2.050034 7.22503 270)
			(size 0.519938 1.4986)
			(layers "F.Cu" "F.Mask" "F.Paste")
			(net "M_E_CPU1_SB_CA<2>")
		)
		(pad "79" smd rect
			(at -2.050034 8.074914 270)
			(size 0.519938 1.4986)
			(layers "F.Cu" "F.Mask" "F.Paste")
			(net "GND")
		)
		(pad "80" smd rect
			(at -2.050034 8.925052 270)
			(size 0.519938 1.4986)
			(layers "F.Cu" "F.Mask" "F.Paste")
			(net "M_E_CPU1_SB_CA<4>")
		)
		(pad "81" smd rect
			(at -2.050034 9.774936 270)
			(size 0.519938 1.4986)
			(layers "F.Cu" "F.Mask" "F.Paste")
			(net "GND")
		)
		(pad "82" smd rect
			(at -2.050034 10.625074 270)
			(size 0.519938 1.4986)
			(layers "F.Cu" "F.Mask" "F.Paste")
			(net "M_E_CPU1_SB_CA<6>")
		)
		(pad "83" smd rect
			(at -2.050034 11.474958 270)
			(size 0.519938 1.4986)
			(layers "F.Cu" "F.Mask" "F.Paste")
			(net "GND")
		)
		(pad "84" smd rect
			(at -2.050034 12.325096 270)
			(size 0.519938 1.4986)
			(layers "F.Cu" "F.Mask" "F.Paste")
			(net "M_E_CPU1_SB_CS_N<2>")
		)
		(pad "85" smd rect
			(at -2.050034 13.17498 270)
			(size 0.519938 1.4986)
			(layers "F.Cu" "F.Mask" "F.Paste")
			(net "GND")
		)
		(pad "86" smd rect
			(at -2.050034 14.025118 270)
			(size 0.519938 1.4986)
			(layers "F.Cu" "F.Mask" "F.Paste")
			(net "M_E_CPU1_SA_RSP<1>")
		)
		(pad "87" smd rect
			(at -2.050034 14.875002 270)
			(size 0.519938 1.4986)
			(layers "F.Cu" "F.Mask" "F.Paste")
			(net "M_E_CPU1_SB_RSP<1>")
		)
		(pad "88" smd rect
			(at -2.050034 15.724886 270)
			(size 0.519938 1.4986)
			(layers "F.Cu" "F.Mask" "F.Paste")
			(net "GND")
		)
		(pad "89" smd rect
			(at -2.050034 16.575024 270)
			(size 0.519938 1.4986)
			(layers "F.Cu" "F.Mask" "F.Paste")
			(net "M_E_CPU1_SB_CB<4>")
		)
		(pad "90" smd rect
			(at -2.050034 17.424908 270)
			(size 0.519938 1.4986)
			(layers "F.Cu" "F.Mask" "F.Paste")
			(net "GND")
		)
		(pad "91" smd rect
			(at -2.050034 18.275046 270)
			(size 0.519938 1.4986)
			(layers "F.Cu" "F.Mask" "F.Paste")
			(net "M_E_CPU1_SB_CB<5>")
		)
		(pad "92" smd rect
			(at -2.050034 19.12493 270)
			(size 0.519938 1.4986)
			(layers "F.Cu" "F.Mask" "F.Paste")
			(net "GND")
		)
		(pad "93" smd rect
			(at -2.050034 19.975068 270)
			(size 0.519938 1.4986)
			(layers "F.Cu" "F.Mask" "F.Paste")
			(net "M_E_CPU1_SB_DQS_DP<9>")
		)
		(pad "94" smd rect
			(at -2.050034 20.824952 270)
			(size 0.519938 1.4986)
			(layers "F.Cu" "F.Mask" "F.Paste")
			(net "M_E_CPU1_SB_DQS_DN<9>")
		)
		(pad "95" smd rect
			(at -2.050034 21.67509 270)
			(size 0.519938 1.4986)
			(layers "F.Cu" "F.Mask" "F.Paste")
			(net "GND")
		)
		(pad "96" smd rect
			(at -2.050034 22.524974 270)
			(size 0.519938 1.4986)
			(layers "F.Cu" "F.Mask" "F.Paste")
			(net "M_E_CPU1_SB_CB<0>")
		)
		(pad "97" smd rect
			(at -2.050034 23.375112 270)
			(size 0.519938 1.4986)
			(layers "F.Cu" "F.Mask" "F.Paste")
			(net "GND")
		)
		(pad "98" smd rect
			(at -2.050034 24.224996 270)
			(size 0.519938 1.4986)
			(layers "F.Cu" "F.Mask" "F.Paste")
			(net "M_E_CPU1_SB_CB<1>")
		)
		(pad "99" smd rect
			(at -2.050034 25.07488 270)
			(size 0.519938 1.4986)
			(layers "F.Cu" "F.Mask" "F.Paste")
			(net "GND")
		)
		(pad "100" smd rect
			(at -2.050034 25.925018 270)
			(size 0.519938 1.4986)
			(layers "F.Cu" "F.Mask" "F.Paste")
			(net "M_E_CPU1_SB_DQ<0>")
		)
		(pad "101" smd rect
			(at -2.050034 26.774902 270)
			(size 0.519938 1.4986)
			(layers "F.Cu" "F.Mask" "F.Paste")
			(net "GND")
		)
		(pad "102" smd rect
			(at -2.050034 27.62504 270)
			(size 0.519938 1.4986)
			(layers "F.Cu" "F.Mask" "F.Paste")
			(net "M_E_CPU1_SB_DQ<1>")
		)
		(pad "103" smd rect
			(at -2.050034 28.474924 270)
			(size 0.519938 1.4986)
			(layers "F.Cu" "F.Mask" "F.Paste")
			(net "GND")
		)
		(pad "104" smd rect
			(at -2.050034 29.325062 270)
			(size 0.519938 1.4986)
			(layers "F.Cu" "F.Mask" "F.Paste")
			(net "M_E_CPU1_SB_DQS_DP<0>")
		)
		(pad "105" smd rect
			(at -2.050034 30.174946 270)
			(size 0.519938 1.4986)
			(layers "F.Cu" "F.Mask" "F.Paste")
			(net "M_E_CPU1_SB_DQS_DN<0>")
		)
		(pad "106" smd rect
			(at -2.050034 31.025084 270)
			(size 0.519938 1.4986)
			(layers "F.Cu" "F.Mask" "F.Paste")
			(net "GND")
		)
		(pad "107" smd rect
			(at -2.050034 31.874968 270)
			(size 0.519938 1.4986)
			(layers "F.Cu" "F.Mask" "F.Paste")
			(net "M_E_CPU1_SB_DQ<4>")
		)
		(pad "108" smd rect
			(at -2.050034 32.725106 270)
			(size 0.519938 1.4986)
			(layers "F.Cu" "F.Mask" "F.Paste")
			(net "GND")
		)
		(pad "109" smd rect
			(at -2.050034 33.57499 270)
			(size 0.519938 1.4986)
			(layers "F.Cu" "F.Mask" "F.Paste")
			(net "M_E_CPU1_SB_DQ<5>")
		)
		(pad "110" smd rect
			(at -2.050034 34.425128 270)
			(size 0.519938 1.4986)
			(layers "F.Cu" "F.Mask" "F.Paste")
			(net "GND")
		)
		(pad "111" smd rect
			(at -2.050034 35.275012 270)
			(size 0.519938 1.4986)
			(layers "F.Cu" "F.Mask" "F.Paste")
			(net "M_E_CPU1_SB_DQ<8>")
		)
		(pad "112" smd rect
			(at -2.050034 36.124896 270)
			(size 0.519938 1.4986)
			(layers "F.Cu" "F.Mask" "F.Paste")
			(net "GND")
		)
	)
)
